FILE_TYPE = CONNECTIVITY;
{Allegro Design Entry HDL 17.2-2016 S081 (4005846) 1/11/2022}
"PAGE_NUMBER" = 44;
0"NC";
1"GND\g";
2"GND\g";
3"GND\g";
4"GND\g";
5"GND\g";
6"GND\g";
7"P3V3_AUX\g";
8"P3V3_AUX\g";
9"P3V3_AUX\g";
10"SPI_PCH_MUXED_IO2";
11"SPI_PCH_MUXED_IO1";
12"SPI_PCH_MUXED_CS0_N";
13"SPI_PCH_MUXED_CLK";
14"SPI_PCH_MUXED_IO3";
15"SPI_PCH_MUXED_IO0";
16"SPI_BMC_BIOS_ROM_R_IO3";
17"SPI_SYS_MUX_MOSI";
18"SPI_BMC_BIOS_ROM_R_MOSI";
19"SPI_SYS_MUX_MISO";
20"SPI_SYS_MUX_MOSI";
21"SPI_SYS_MUX_CLK";
22"SPI_BMC_BIOS_CS0_N";
23"SPI_SYS_R_CLK";
24"SPI_BMC_BIOS_ROM_IO3";
25"SPI_BMC_BIOS_ROM_IO2";
26"SPI_BMC_BIOS_ROM_MISO";
27"SPI_BMC_BIOS_ROM_MOSI";
28"SPI_SYS_R_MOSI";
29"SPI_SYS_R_MISO";
30"SPI_SYS_WP_R_IO2";
31"SPI_SYS_HOLD_R_IO3";
32"SPI_SYS_CS0_N";
33"SPI_TPM_CS_R_N";
34"FM_BMC_BIOS_MUX_CS_SPI_R_SEL_0";
35"FM_BMC_BIOS_MUX_CS_SPI_R_SEL_0";
36"PD_BIOS_MUX_EN_N";
37"FM_BMC_BIOS_MUX_CS_SPI_R_SEL_0";
38"PD_BIOS_MUX_EN_N";
39"TP_BIOS_MUX1_PIN14";
40"SPI_PCH_SECURE_CS0_N";
41"SPI_BMC_BIOS_SOURCE_CS0_N";
42"SPI_SYS_MUX_MISO";
43"SPI_BMC_BIOS_ROM_R_MISO";
44"SPI_SYS_MUX_WP_IO2";
45"SPI_PCH_SECURE_CS0_N";
46"TP_BIOS_MUX0_PIN13";
47"TP_BIOS_MUX0_PIN14";
48"SPI_SYS_MUX_HOLD_IO3";
49"SPI_SYS_MUX_WP_IO2";
50"SPI_BMC_BIOS_SOURCE_CS0_N";
51"SPI_BMC_BIOS_ROM_R_IO3";
52"SPI_BMC_BIOS_ROM_R_IO2";
53"SPI_BMC_BIOS_ROM_R_MISO";
54"SPI_BMC_BIOS_ROM_R_MOSI";
55"SPI_BMC_BIOS_ROM_R_CLK";
56"SPI_BMC_BIOS_ROM_CLK";
57"FM_BMC_MUX_CS_SPI_SEL_0";
58"SPI_TPM_CS_N";
59"TP_BIOS_MUX0_PIN12";
60"SPI_SYS_MUX_HOLD_IO3";
61"TP_BIOS_MUX1_PIN13";
62"SPI_BMC_BIOS_ROM_R_CLK";
63"SPI_SYS_MUX_CLK";
64"TP_BIOS_MUX1_PIN12";
65"SPI_BMC_BIOS_ROM_R_IO2";
%"IDTQS3VH257PAG"
"1","(2325,1050)","2","pure_quanta","I271";
;
PART_NUMBER"AL000257K00"
VALUE"IDTQS3VH257PAG"
MATERIAL"IC"
SEC_TYPE"SMLF"
PACK_TYPE"SMLF"
MANUF_PN"IDTQS3VH257PAG"
CDS_LIB"pure_quanta"
CDS_LMAN_SYM_OUTLINE"-250,400,250,-500"
LOCATION"U30"
SEC"1";
"VCC"
$PN"16"9;
"YB"
$PN"7"14;
"I_1D"
$PN"13"46;
"I_0D"
$PN"14"47;
"I_0C"
$PN"11"63;
"I_1C"
$PN"10"62;
"I_0B"
$PN"5"60;
"I_1B"
$PN"6"16;
"I_1A"
$PN"3"18;
"I_0A"
$PN"2"17;
"S"
$PN"1"35;
"YD"
$PN"12"59;
"YC"
$PN"9"13;
"YA"
$PN"4"15;
"E* \B"
$PN"15"36;
"GND"
$PN"8"2;
%"UNIVERSAL_GND"
"1","(3275,600)","0","logical_power","I272";
;
CDS_LIB"logical_power"
HDL_POWER"GND";
"A"2;
%"P3V3_AUX"
"1","(2925,1850)","0","logical_power","I276";
;
CDS_LIB"logical_power"
SIZE"1B"
BODY_TYPE"PLUMBING"
HDL_POWER"P3V3_AUX";
"G<SIZE-1..0>\NAC"9;
%"UNIVERSAL_GND"
"1","(3100,1400)","2","logical_power","I277";
;
CDS_LIB"logical_power"
HDL_POWER"GND";
"A"1;
%"Q_CAP"
"1","(3100,1600)","0","pure_quanta","I278";
;
VOLTAGE"25V"
PACK_TYPE"0402"
TOLERANCE"10%"
VALUE"0.1UF"
PART_NUMBER"CH4104K1B00"
MATERIAL"X7R"
CDS_LIB"pure_quanta"
LOCATION"C255"
$SEC"1"
CDS_SEC"1";
"B"
$PN"2"1;
"A"
$PN"1"9;
%"Q_CAP"
"1","(3125,-100)","0","pure_quanta","I292";
;
MATERIAL"X7R"
TOLERANCE"10%"
VALUE"0.1UF"
VOLTAGE"25V"
PART_NUMBER"CH4104K1B00"
PACK_TYPE"0402"
CDS_LIB"pure_quanta"
LOCATION"C146"
$SEC"1"
CDS_SEC"1";
"B"
$PN"2"4;
"A"
$PN"1"8;
%"UNIVERSAL_GND"
"1","(3125,-300)","2","logical_power","I293";
;
CDS_LIB"logical_power"
HDL_POWER"GND";
"A"4;
%"UNIVERSAL_GND"
"1","(3300,-1100)","0","logical_power","I294";
;
CDS_LIB"logical_power"
HDL_POWER"GND";
"A"3;
%"P3V3_AUX"
"1","(2950,150)","0","logical_power","I295";
;
SIZE"1B"
CDS_LIB"logical_power"
BODY_TYPE"PLUMBING"
HDL_POWER"P3V3_AUX";
"G<SIZE-1..0>\NAC"8;
%"IDTQS3VH257PAG"
"1","(2350,-650)","2","pure_quanta","I296";
;
VALUE"IDTQS3VH257PAG"
PART_NUMBER"AL000257K00"
MATERIAL"IC"
CDS_LMAN_SYM_OUTLINE"-250,400,250,-500"
CDS_LIB"pure_quanta"
MANUF_PN"IDTQS3VH257PAG"
SEC_TYPE"SMLF"
PACK_TYPE"SMLF"
LOCATION"U21"
SEC"1";
"VCC"
$PN"16"8;
"YB"
$PN"7"11;
"I_1D"
$PN"13"61;
"I_0D"
$PN"14"39;
"I_0C"
$PN"11"40;
"I_1C"
$PN"10"41;
"I_0B"
$PN"5"42;
"I_1B"
$PN"6"43;
"I_1A"
$PN"3"65;
"I_0A"
$PN"2"44;
"S"
$PN"1"37;
"YD"
$PN"12"64;
"YC"
$PN"9"12;
"YA"
$PN"4"10;
"E* \B"
$PN"15"38;
"GND"
$PN"8"3;
%"Q_RES"
"2","(1775,-1450)","2","pure_quanta","I311";
;
PART_NUMBER"CS31002FB08"
TOLERANCE"1%"
WATTAGE"1/16W"
MATERIAL"CHIP"
VALUE"10K"
PACK_TYPE"0402LF"
CDS_LIB"pure_quanta"
LOCATION"R866"
$SEC"1"
CDS_SEC"1";
"A"
$PN"1"37;
"B"
$PN"2"5;
%"UNIVERSAL_GND"
"1","(1775,-1650)","0","logical_power","I312";
;
CDS_LIB"logical_power"
HDL_POWER"GND";
"A"5;
%"Q_RES"
"2","(1250,-1375)","0","pure_quanta","I313";
;
TOLERANCE"1%"
VALUE"2K"
PACK_TYPE"0402LF"
MATERIAL"CHIP"
WATTAGE"1/16W"
CDS_LIB"pure_quanta"
PART_NUMBER"CS22002FB07"
LOCATION"R467"
$SEC"1"
CDS_SEC"1";
"A"
$PN"1"38;
"B"
$PN"2"6;
%"UNIVERSAL_GND"
"1","(1250,-1575)","0","logical_power","I314";
;
CDS_LIB"logical_power"
HDL_POWER"GND";
"A"6;
%"Q_RES"
"2","(475,-1400)","2","pure_quanta","I315";
;
PART_NUMBER"CS24702FB06"
MATERIAL"EMPTY"
WATTAGE"1/16W"
TOLERANCE"1%"
VALUE"4.7K"
PACK_TYPE"0402LF"
CDS_LIB"pure_quanta"
LOCATION"R870"
$SEC"1"
CDS_SEC"1";
"A"
$PN"1"7;
"B"
$PN"2"38;
%"P3V3_AUX"
"1","(475,-1200)","0","logical_power","I316";
;
CDS_LIB"logical_power"
SIZE"1B"
BODY_TYPE"PLUMBING"
HDL_POWER"P3V3_AUX";
"G<SIZE-1..0>\NAC"7;
%"Q_RES"
"1","(-2625,2625)","0","pure_quanta","I330";
;
MATERIAL"CHIP"
VALUE"33.2"
CDS_LIB"pure_quanta"
WATTAGE"1/16W"
PACK_TYPE"0402LF"
PART_NUMBER"CS03322FB03"
TOLERANCE"1%"
LOCATION"R175"
$SEC"1"
CDS_SEC"1";
"B"
$PN"2"54;
"A"
$PN"1"27;
%"Q_RES"
"1","(-2625,2675)","0","pure_quanta","I331";
;
MATERIAL"CHIP"
VALUE"33.2"
CDS_LIB"pure_quanta"
WATTAGE"1/16W"
PACK_TYPE"0402LF"
PART_NUMBER"CS03322FB03"
TOLERANCE"1%"
LOCATION"R174"
$SEC"1"
CDS_SEC"1";
"B"
$PN"2"55;
"A"
$PN"1"56;
%"Q_RES"
"1","(-2625,2575)","0","pure_quanta","I332";
;
MATERIAL"CHIP"
VALUE"33.2"
CDS_LIB"pure_quanta"
WATTAGE"1/16W"
PACK_TYPE"0402LF"
PART_NUMBER"CS03322FB03"
TOLERANCE"1%"
LOCATION"R176"
$SEC"1"
CDS_SEC"1";
"B"
$PN"2"53;
"A"
$PN"1"26;
%"Q_RES"
"1","(-2625,2525)","0","pure_quanta","I333";
;
MATERIAL"CHIP"
VALUE"33.2"
CDS_LIB"pure_quanta"
WATTAGE"1/16W"
PACK_TYPE"0402LF"
PART_NUMBER"CS03322FB03"
TOLERANCE"1%"
LOCATION"R724"
$SEC"1"
CDS_SEC"1";
"B"
$PN"2"52;
"A"
$PN"1"25;
%"Q_RES"
"1","(-2625,2475)","0","pure_quanta","I334";
;
MATERIAL"CHIP"
VALUE"33.2"
CDS_LIB"pure_quanta"
WATTAGE"1/16W"
PACK_TYPE"0402LF"
PART_NUMBER"CS03322FB03"
TOLERANCE"1%"
LOCATION"R725"
$SEC"1"
CDS_SEC"1";
"B"
$PN"2"51;
"A"
$PN"1"24;
%"Q_RES"
"1","(-2625,2300)","0","pure_quanta","I336";
;
VALUE"0"
PART_NUMBER"CS00002JB13"
MATERIAL"CHIP"
CDS_LIB"pure_quanta"
TOLERANCE"5%"
WATTAGE"1/16W"
PACK_TYPE"0402LF"
LOCATION"R728"
$SEC"1"
CDS_SEC"1";
"B"
$PN"2"50;
"A"
$PN"1"22;
%"Q_RES"
"1","(-2600,1700)","0","pure_quanta","I339";
;
MATERIAL"CHIP"
VALUE"33.2"
CDS_LIB"pure_quanta"
WATTAGE"1/16W"
PACK_TYPE"0402LF"
PART_NUMBER"CS03322FB03"
TOLERANCE"1%"
LOCATION"R859"
$SEC"1"
CDS_SEC"1";
"B"
$PN"2"21;
"A"
$PN"1"23;
%"Q_RES"
"1","(-2600,1450)","0","pure_quanta","I342";
;
MATERIAL"CHIP"
VALUE"33.2"
CDS_LIB"pure_quanta"
WATTAGE"1/16W"
PACK_TYPE"0402LF"
PART_NUMBER"CS03322FB03"
TOLERANCE"1%"
LOCATION"R864"
$SEC"1"
CDS_SEC"1";
"B"
$PN"2"45;
"A"
$PN"1"32;
%"Q_RES"
"1","(-2425,-125)","0","pure_quanta","I360";
;
VALUE"33.2"
MATERIAL"CHIP"
TOLERANCE"1%"
PART_NUMBER"CS03322FB03"
PACK_TYPE"0402LF"
WATTAGE"1/16W"
CDS_LIB"pure_quanta"
LOCATION"R594"
$SEC"1"
CDS_SEC"1";
"B"
$PN"2"33;
"A"
$PN"1"58;
%"Q_RES"
"1","(-2600,1650)","0","pure_quanta","I362";
;
MATERIAL"CHIP"
PART_NUMBER"CS02202FB02"
VALUE"22"
CDS_LIB"pure_quanta"
TOLERANCE"1%"
WATTAGE"1/16W"
PACK_TYPE"0402LF"
LOCATION"R860"
$SEC"1"
CDS_SEC"1";
"B"
$PN"2"20;
"A"
$PN"1"28;
%"Q_RES"
"1","(-2600,1600)","0","pure_quanta","I363";
;
MATERIAL"CHIP"
VALUE"22"
CDS_LIB"pure_quanta"
PART_NUMBER"CS02202FB02"
TOLERANCE"1%"
WATTAGE"1/16W"
PACK_TYPE"0402LF"
LOCATION"R861"
$SEC"1"
CDS_SEC"1";
"B"
$PN"2"19;
"A"
$PN"1"29;
%"Q_RES"
"1","(-2600,1550)","0","pure_quanta","I364";
;
MATERIAL"CHIP"
VALUE"22"
PART_NUMBER"CS02202FB02"
TOLERANCE"1%"
WATTAGE"1/16W"
PACK_TYPE"0402LF"
CDS_LIB"pure_quanta"
LOCATION"R862"
$SEC"1"
CDS_SEC"1";
"B"
$PN"2"49;
"A"
$PN"1"30;
%"Q_RES"
"1","(-2600,1500)","0","pure_quanta","I365";
;
MATERIAL"CHIP"
VALUE"22"
CDS_LIB"pure_quanta"
PACK_TYPE"0402LF"
WATTAGE"1/16W"
TOLERANCE"1%"
PART_NUMBER"CS02202FB02"
LOCATION"R863"
$SEC"1"
CDS_SEC"1";
"B"
$PN"2"48;
"A"
$PN"1"31;
%"Q_RES"
"1","(-2425,225)","0","pure_quanta","I366";
;
VALUE"68.1"
PART_NUMBER"CS06812FB03"
MATERIAL"CHIP"
PACK_TYPE"0402LF"
TOLERANCE"1%"
WATTAGE"1/16W"
CDS_LIB"pure_quanta"
LOCATION"R852"
$SEC"1"
CDS_SEC"1";
"B"
$PN"2"34;
"A"
$PN"1"57;
END.
